(kicad_pcb
	(version 20241229)
	(generator "pcbnew")
	(generator_version "9.0")
	(general
		(thickness 1.6296)
		(legacy_teardrops no)
	)
	(paper "A3")
	(title_block
		(title "Thunderbolt to 10GbE adapter")
		(date "2026-04-21")
		(rev "1.1.0")
		(company "Antmicro Ltd")
		(comment 1 "www.antmicro.com")
		(comment 9 "footprints 436-440 of 703")
	)
	(layers
		(0 "F.Cu" signal)
		(4 "In1.Cu" signal)
		(6 "In2.Cu" signal)
		(8 "In3.Cu" signal)
		(10 "In4.Cu" signal)
		(12 "In5.Cu" signal)
		(14 "In6.Cu" signal)
		(2 "B.Cu" signal)
		(9 "F.Adhes" user "F.Adhesive")
		(11 "B.Adhes" user "B.Adhesive")
		(13 "F.Paste" user)
		(15 "B.Paste" user)
		(5 "F.SilkS" user "F.Silkscreen")
		(7 "B.SilkS" user "B.Silkscreen")
		(1 "F.Mask" user)
		(3 "B.Mask" user)
		(17 "Dwgs.User" user "User.Drawings")
		(19 "Cmts.User" user "User.Comments")
		(21 "Eco1.User" user "User.Eco1")
		(23 "Eco2.User" user "User.Eco2")
		(25 "Edge.Cuts" user)
		(27 "Margin" user)
		(31 "F.CrtYd" user "F.Courtyard")
		(29 "B.CrtYd" user "B.Courtyard")
		(35 "F.Fab" user)
		(33 "B.Fab" user)
	)
	(footprint "antmicro-footprints:R_0402_1005Metric"
		(layer "B.Cu")
		(at 145.631865 83.260117 180)
		(descr "Resistor SMD 0402")
		(tags "resistor SMD 0402")
		(property "Reference" "R121"
			(at -17.768134 -9.464883 0)
			(layer "B.SilkS")
			(effects
				(font
					(size 0.7 0.7)
					(thickness 0.15)
				)
				(justify mirror)
			)
		)
		(property "Value" "R_100R_0402"
			(at -1.011843 -1.772047 0)
			(layer "B.Fab")
			(effects
				(font
					(size 0.7 0.7)
					(thickness 0.15)
				)
				(justify left bottom mirror)
			)
		)
		(property "Datasheet" "https://www.bourns.com/docs/product-datasheets/cr.pdf"
			(at 0 0 0)
			(layer "B.Fab")
			(hide yes)
			(effects
				(font
					(size 1.27 1.27)
					(thickness 0.15)
				)
				(justify mirror)
			)
		)
		(property "Description" "SMD Chip Resistor, 100 ohm, ± 1%, 62.5 mW, 0402 [1005 Metric], Thick Film, General Purpose"
			(at 0 0 0)
			(layer "B.Fab")
			(hide yes)
			(effects
				(font
					(size 1.27 1.27)
					(thickness 0.15)
				)
				(justify mirror)
			)
		)
		(property "MPN" "CR0402-FX-1000GLF"
			(at 0 0 180)
			(unlocked yes)
			(layer "B.Fab")
			(hide yes)
			(effects
				(font
					(size 1 1)
					(thickness 0.15)
				)
				(justify mirror)
			)
		)
		(property "Manufacturer" "Bourns"
			(at 0 0 180)
			(unlocked yes)
			(layer "B.Fab")
			(hide yes)
			(effects
				(font
					(size 1 1)
					(thickness 0.15)
				)
				(justify mirror)
			)
		)
		(property "License" "Apache-2.0"
			(at 0 0 180)
			(unlocked yes)
			(layer "B.Fab")
			(hide yes)
			(effects
				(font
					(size 1 1)
					(thickness 0.15)
				)
				(justify mirror)
			)
		)
		(property "Author" "Antmicro"
			(at 0 0 180)
			(unlocked yes)
			(layer "B.Fab")
			(hide yes)
			(effects
				(font
					(size 1 1)
					(thickness 0.15)
				)
				(justify mirror)
			)
		)
		(property "Val" "100R"
			(at 0 0 180)
			(unlocked yes)
			(layer "B.Fab")
			(hide yes)
			(effects
				(font
					(size 1 1)
					(thickness 0.15)
				)
				(justify mirror)
			)
		)
		(property "Tolerance" "1%"
			(at 0 0 180)
			(unlocked yes)
			(layer "B.Fab")
			(hide yes)
			(effects
				(font
					(size 1 1)
					(thickness 0.15)
				)
				(justify mirror)
			)
		)
		(sheetname "/X710-AT2 RSVD/")
		(sheetfile "x710-at2-rsvd.kicad_sch")
		(attr smd)
		(fp_rect
			(start -0.925 0.47)
			(end 0.925 -0.47)
			(stroke
				(width 0.05)
				(type default)
			)
			(fill no)
			(layer "B.CrtYd")
		)
		(fp_rect
			(start -0.5 0.25)
			(end 0.5 -0.25)
			(stroke
				(width 0.15)
				(type solid)
			)
			(fill no)
			(layer "B.Fab")
		)
		(fp_text user "License: Apache-2.0"
			(at -0.95 -5.169 0)
			(layer "B.Fab")
			(effects
				(font
					(size 0.7 0.7)
					(thickness 0.15)
				)
				(justify left bottom mirror)
			)
		)
		(fp_text user "${REFERENCE}"
			(at -0.95 -3.168 0)
			(layer "B.Fab")
			(effects
				(font
					(size 0.7 0.7)
					(thickness 0.15)
				)
				(justify left bottom mirror)
			)
		)
		(fp_text user "Author: Antmicro"
			(at -0.95 -4.169 0)
			(layer "B.Fab")
			(effects
				(font
					(size 0.7 0.7)
					(thickness 0.15)
				)
				(justify left bottom mirror)
			)
		)
		(pad "1" smd roundrect
			(at -0.48 0 180)
			(size 0.59 0.64)
			(layers "B.Cu" "B.Mask" "B.Paste")
			(roundrect_rratio 0.25)
			(net 23 "GND")
			(pintype "passive")
		)
		(pad "2" smd roundrect
			(at 0.48 0 180)
			(size 0.59 0.64)
			(layers "B.Cu" "B.Mask" "B.Paste")
			(roundrect_rratio 0.25)
			(net 92 "/X710-AT2 RSVD/RSVDY24_VSS")
			(pintype "passive")
		)
	)
	(footprint "antmicro-footprints:C_0402_1005Metric"
		(layer "B.Cu")
		(at 156.111866 87.085117 180)
		(descr "Capacitor SMD 0402")
		(tags "capacitor SMD 0402")
		(property "Reference" "C184"
			(at -19.873134 -9.464883 0)
			(layer "B.SilkS")
			(effects
				(font
					(size 0.7 0.7)
					(thickness 0.15)
				)
				(justify mirror)
			)
		)
		(property "Value" "C_1u_25V_0402"
			(at -1.022927 -2.155213 0)
			(layer "B.Fab")
			(effects
				(font
					(size 0.7 0.7)
					(thickness 0.15)
				)
				(justify left bottom mirror)
			)
		)
		(property "Datasheet" "https://www.murata.com/products/productdetail?partno=GRM155R61E105KE11%23"
			(at 0 0 0)
			(layer "B.Fab")
			(hide yes)
			(effects
				(font
					(size 1.27 1.27)
					(thickness 0.15)
				)
				(justify mirror)
			)
		)
		(property "Description" "SMD Multilayer Ceramic Capacitor, 1 µF, 25 V, 0402 [1005 Metric], ± 10%, X5R, GRM Series"
			(at 0 0 0)
			(layer "B.Fab")
			(hide yes)
			(effects
				(font
					(size 1.27 1.27)
					(thickness 0.15)
				)
				(justify mirror)
			)
		)
		(property "MPN" "GRM155R61E105KE11J"
			(at 0 0 180)
			(unlocked yes)
			(layer "B.Fab")
			(hide yes)
			(effects
				(font
					(size 1 1)
					(thickness 0.15)
				)
				(justify mirror)
			)
		)
		(property "Manufacturer" "Murata"
			(at 0 0 180)
			(unlocked yes)
			(layer "B.Fab")
			(hide yes)
			(effects
				(font
					(size 1 1)
					(thickness 0.15)
				)
				(justify mirror)
			)
		)
		(property "License" "Apache-2.0"
			(at 0 0 180)
			(unlocked yes)
			(layer "B.Fab")
			(hide yes)
			(effects
				(font
					(size 1 1)
					(thickness 0.15)
				)
				(justify mirror)
			)
		)
		(property "Author" "Antmicro"
			(at 0 0 180)
			(unlocked yes)
			(layer "B.Fab")
			(hide yes)
			(effects
				(font
					(size 1 1)
					(thickness 0.15)
				)
				(justify mirror)
			)
		)
		(property "Val" "1u"
			(at 0 0 180)
			(unlocked yes)
			(layer "B.Fab")
			(hide yes)
			(effects
				(font
					(size 1 1)
					(thickness 0.15)
				)
				(justify mirror)
			)
		)
		(property "Voltage" "25V"
			(at 0 0 180)
			(unlocked yes)
			(layer "B.Fab")
			(hide yes)
			(effects
				(font
					(size 1 1)
					(thickness 0.15)
				)
				(justify mirror)
			)
		)
		(property "Dielectric" "X5R"
			(at 0 0 180)
			(unlocked yes)
			(layer "B.Fab")
			(hide yes)
			(effects
				(font
					(size 1 1)
					(thickness 0.15)
				)
				(justify mirror)
			)
		)
		(sheetname "/X710-AT2 power/")
		(sheetfile "x710-at2-power.kicad_sch")
		(attr smd)
		(fp_rect
			(start -0.925 0.47)
			(end 0.925 -0.47)
			(stroke
				(width 0.05)
				(type default)
			)
			(fill no)
			(layer "B.CrtYd")
		)
		(fp_line
			(start 0.504 0.25)
			(end 0.504 -0.248)
			(stroke
				(width 0.15)
				(type solid)
			)
			(layer "B.Fab")
		)
		(fp_line
			(start 0.504 -0.248)
			(end -0.494 -0.248)
			(stroke
				(width 0.15)
				(type solid)
			)
			(layer "B.Fab")
		)
		(fp_line
			(start -0.494 0.25)
			(end 0.504 0.25)
			(stroke
				(width 0.15)
				(type solid)
			)
			(layer "B.Fab")
		)
		(fp_line
			(start -0.494 -0.248)
			(end -0.494 0.25)
			(stroke
				(width 0.15)
				(type solid)
			)
			(layer "B.Fab")
		)
		(fp_text user "Author: Antmicro"
			(at -0.939 -3.399 0)
			(layer "B.Fab")
			(effects
				(font
					(size 0.7 0.7)
					(thickness 0.15)
				)
				(justify left bottom mirror)
			)
		)
		(fp_text user "License: Apache-2.0"
			(at -0.939 -5.799 0)
			(layer "B.Fab")
			(effects
				(font
					(size 0.7 0.7)
					(thickness 0.15)
				)
				(justify left bottom mirror)
			)
		)
		(fp_text user "${REFERENCE}"
			(at -0.939 -4.599 0)
			(layer "B.Fab")
			(effects
				(font
					(size 0.7 0.7)
					(thickness 0.15)
				)
				(justify left bottom mirror)
			)
		)
		(pad "1" smd roundrect
			(at -0.48 0 180)
			(size 0.59 0.64)
			(layers "B.Cu" "B.Mask" "B.Paste")
			(roundrect_rratio 0.25)
			(net 23 "GND")
			(pintype "passive")
		)
		(pad "2" smd roundrect
			(at 0.48 0 180)
			(size 0.59 0.64)
			(layers "B.Cu" "B.Mask" "B.Paste")
			(roundrect_rratio 0.25)
			(net 6 "DVDD")
			(pintype "passive")
		)
	)
	(footprint "antmicro-footprints:C_0402_1005Metric"
		(layer "B.Cu")
		(at 158.931867 88.815117)
		(descr "Capacitor SMD 0402")
		(tags "capacitor SMD 0402")
		(property "Reference" "C205"
			(at 20.068133 10.984883 180)
			(layer "B.SilkS")
			(effects
				(font
					(size 0.7 0.7)
					(thickness 0.15)
				)
				(justify mirror)
			)
		)
		(property "Value" "C_1u_25V_0402"
			(at -1.022927 -2.155213 180)
			(layer "B.Fab")
			(effects
				(font
					(size 0.7 0.7)
					(thickness 0.15)
				)
				(justify left bottom mirror)
			)
		)
		(property "Datasheet" "https://www.murata.com/products/productdetail?partno=GRM155R61E105KE11%23"
			(at 0 0 180)
			(layer "B.Fab")
			(hide yes)
			(effects
				(font
					(size 1.27 1.27)
					(thickness 0.15)
				)
				(justify mirror)
			)
		)
		(property "Description" "SMD Multilayer Ceramic Capacitor, 1 µF, 25 V, 0402 [1005 Metric], ± 10%, X5R, GRM Series"
			(at 0 0 180)
			(layer "B.Fab")
			(hide yes)
			(effects
				(font
					(size 1.27 1.27)
					(thickness 0.15)
				)
				(justify mirror)
			)
		)
		(property "MPN" "GRM155R61E105KE11J"
			(at 0 0 0)
			(unlocked yes)
			(layer "B.Fab")
			(hide yes)
			(effects
				(font
					(size 1 1)
					(thickness 0.15)
				)
				(justify mirror)
			)
		)
		(property "Manufacturer" "Murata"
			(at 0 0 0)
			(unlocked yes)
			(layer "B.Fab")
			(hide yes)
			(effects
				(font
					(size 1 1)
					(thickness 0.15)
				)
				(justify mirror)
			)
		)
		(property "License" "Apache-2.0"
			(at 0 0 0)
			(unlocked yes)
			(layer "B.Fab")
			(hide yes)
			(effects
				(font
					(size 1 1)
					(thickness 0.15)
				)
				(justify mirror)
			)
		)
		(property "Author" "Antmicro"
			(at 0 0 0)
			(unlocked yes)
			(layer "B.Fab")
			(hide yes)
			(effects
				(font
					(size 1 1)
					(thickness 0.15)
				)
				(justify mirror)
			)
		)
		(property "Val" "1u"
			(at 0 0 0)
			(unlocked yes)
			(layer "B.Fab")
			(hide yes)
			(effects
				(font
					(size 1 1)
					(thickness 0.15)
				)
				(justify mirror)
			)
		)
		(property "Voltage" "25V"
			(at 0 0 0)
			(unlocked yes)
			(layer "B.Fab")
			(hide yes)
			(effects
				(font
					(size 1 1)
					(thickness 0.15)
				)
				(justify mirror)
			)
		)
		(property "Dielectric" "X5R"
			(at 0 0 0)
			(unlocked yes)
			(layer "B.Fab")
			(hide yes)
			(effects
				(font
					(size 1 1)
					(thickness 0.15)
				)
				(justify mirror)
			)
		)
		(sheetname "/X710-AT2 power/")
		(sheetfile "x710-at2-power.kicad_sch")
		(attr smd)
		(fp_rect
			(start -0.925 0.47)
			(end 0.925 -0.47)
			(stroke
				(width 0.05)
				(type default)
			)
			(fill no)
			(layer "B.CrtYd")
		)
		(fp_line
			(start -0.494 -0.248)
			(end -0.494 0.25)
			(stroke
				(width 0.15)
				(type solid)
			)
			(layer "B.Fab")
		)
		(fp_line
			(start -0.494 0.25)
			(end 0.504 0.25)
			(stroke
				(width 0.15)
				(type solid)
			)
			(layer "B.Fab")
		)
		(fp_line
			(start 0.504 -0.248)
			(end -0.494 -0.248)
			(stroke
				(width 0.15)
				(type solid)
			)
			(layer "B.Fab")
		)
		(fp_line
			(start 0.504 0.25)
			(end 0.504 -0.248)
			(stroke
				(width 0.15)
				(type solid)
			)
			(layer "B.Fab")
		)
		(fp_text user "License: Apache-2.0"
			(at -0.939 -5.799 180)
			(layer "B.Fab")
			(effects
				(font
					(size 0.7 0.7)
					(thickness 0.15)
				)
				(justify left bottom mirror)
			)
		)
		(fp_text user "${REFERENCE}"
			(at -0.939 -4.599 180)
			(layer "B.Fab")
			(effects
				(font
					(size 0.7 0.7)
					(thickness 0.15)
				)
				(justify left bottom mirror)
			)
		)
		(fp_text user "Author: Antmicro"
			(at -0.939 -3.399 180)
			(layer "B.Fab")
			(effects
				(font
					(size 0.7 0.7)
					(thickness 0.15)
				)
				(justify left bottom mirror)
			)
		)
		(pad "1" smd roundrect
			(at -0.48 0)
			(size 0.59 0.64)
			(layers "B.Cu" "B.Mask" "B.Paste")
			(roundrect_rratio 0.25)
			(net 23 "GND")
			(pintype "passive")
		)
		(pad "2" smd roundrect
			(at 0.48 0)
			(size 0.59 0.64)
			(layers "B.Cu" "B.Mask" "B.Paste")
			(roundrect_rratio 0.25)
			(net 5 "P0_AVDDL")
			(pintype "passive")
		)
	)
	(footprint "antmicro-footprints:R_0402_1005Metric"
		(layer "B.Cu")
		(at 148.425 84.925 180)
		(descr "Resistor SMD 0402")
		(tags "resistor SMD 0402")
		(property "Reference" "R179"
			(at -17.975 -9.475 0)
			(layer "B.SilkS")
			(effects
				(font
					(size 0.7 0.7)
					(thickness 0.15)
				)
				(justify mirror)
			)
		)
		(property "Value" "R_10k_0402"
			(at -1.011843 -1.772047 0)
			(layer "B.Fab")
			(effects
				(font
					(size 0.7 0.7)
					(thickness 0.15)
				)
				(justify left bottom mirror)
			)
		)
		(property "Datasheet" "https://www.bourns.com/docs/product-datasheets/cr.pdf"
			(at 0 0 0)
			(layer "B.Fab")
			(hide yes)
			(effects
				(font
					(size 1.27 1.27)
					(thickness 0.15)
				)
				(justify mirror)
			)
		)
		(property "Description" "SMD Chip Resistor, 10 kohm, ± 1%, 62.5 mW, 0402 [1005 Metric], Thick Film, General Purpose"
			(at 0 0 0)
			(layer "B.Fab")
			(hide yes)
			(effects
				(font
					(size 1.27 1.27)
					(thickness 0.15)
				)
				(justify mirror)
			)
		)
		(property "MPN" "CR0402-FX-1002GLF"
			(at 0 0 180)
			(unlocked yes)
			(layer "B.Fab")
			(hide yes)
			(effects
				(font
					(size 1 1)
					(thickness 0.15)
				)
				(justify mirror)
			)
		)
		(property "Manufacturer" "Bourns"
			(at 0 0 180)
			(unlocked yes)
			(layer "B.Fab")
			(hide yes)
			(effects
				(font
					(size 1 1)
					(thickness 0.15)
				)
				(justify mirror)
			)
		)
		(property "License" "Apache-2.0"
			(at 0 0 180)
			(unlocked yes)
			(layer "B.Fab")
			(hide yes)
			(effects
				(font
					(size 1 1)
					(thickness 0.15)
				)
				(justify mirror)
			)
		)
		(property "Author" "Antmicro"
			(at 0 0 180)
			(unlocked yes)
			(layer "B.Fab")
			(hide yes)
			(effects
				(font
					(size 1 1)
					(thickness 0.15)
				)
				(justify mirror)
			)
		)
		(property "Val" "10k"
			(at 0 0 180)
			(unlocked yes)
			(layer "B.Fab")
			(hide yes)
			(effects
				(font
					(size 1 1)
					(thickness 0.15)
				)
				(justify mirror)
			)
		)
		(property "Tolerance" "1%"
			(at 0 0 180)
			(unlocked yes)
			(layer "B.Fab")
			(hide yes)
			(effects
				(font
					(size 1 1)
					(thickness 0.15)
				)
				(justify mirror)
			)
		)
		(sheetname "/X710-AT2 Misc/")
		(sheetfile "x710-at2-mics.kicad_sch")
		(attr smd)
		(fp_rect
			(start -0.925 0.47)
			(end 0.925 -0.47)
			(stroke
				(width 0.05)
				(type default)
			)
			(fill no)
			(layer "B.CrtYd")
		)
		(fp_rect
			(start -0.5 0.25)
			(end 0.5 -0.25)
			(stroke
				(width 0.15)
				(type solid)
			)
			(fill no)
			(layer "B.Fab")
		)
		(fp_text user "License: Apache-2.0"
			(at -0.95 -5.169 0)
			(layer "B.Fab")
			(effects
				(font
					(size 0.7 0.7)
					(thickness 0.15)
				)
				(justify left bottom mirror)
			)
		)
		(fp_text user "Author: Antmicro"
			(at -0.95 -4.169 0)
			(layer "B.Fab")
			(effects
				(font
					(size 0.7 0.7)
					(thickness 0.15)
				)
				(justify left bottom mirror)
			)
		)
		(fp_text user "${REFERENCE}"
			(at -0.95 -3.168 0)
			(layer "B.Fab")
			(effects
				(font
					(size 0.7 0.7)
					(thickness 0.15)
				)
				(justify left bottom mirror)
			)
		)
		(pad "1" smd roundrect
			(at -0.48 0 180)
			(size 0.59 0.64)
			(layers "B.Cu" "B.Mask" "B.Paste")
			(roundrect_rratio 0.25)
			(net 444 "Net-(U14D-SMBCLK)")
			(pintype "passive")
		)
		(pad "2" smd roundrect
			(at 0.48 0 180)
			(size 0.59 0.64)
			(layers "B.Cu" "B.Mask" "B.Paste")
			(roundrect_rratio 0.25)
			(net 7 "+3V3")
			(pintype "passive")
		)
	)
	(footprint "antmicro-footprints:TP_SMD_0.75mm"
		(layer "B.Cu")
		(at 140.25 57.75 90)
		(property "Reference" "TP37"
			(at 3.15 0.45 270)
			(layer "B.SilkS")
			(effects
				(font
					(size 0.7 0.7)
					(thickness 0.15)
				)
				(justify left bottom mirror)
			)
		)
		(property "Value" "TP_0.75mm_SMD"
			(at 0 -1.2 270)
			(layer "B.Fab")
			(effects
				(font
					(size 0.7 0.7)
					(thickness 0.15)
				)
				(justify left bottom mirror)
			)
		)
		(property "Description" "SMT test point"
			(at 0 0 270)
			(layer "B.Fab")
			(hide yes)
			(effects
				(font
					(size 1.27 1.27)
					(thickness 0.15)
				)
				(justify mirror)
			)
		)
		(property "MPN" ""
			(at 0 0 90)
			(unlocked yes)
			(layer "B.Fab")
			(hide yes)
			(effects
				(font
					(size 1 1)
					(thickness 0.15)
				)
				(justify mirror)
			)
		)
		(property "Manufacturer" ""
			(at 0 0 90)
			(unlocked yes)
			(layer "B.Fab")
			(hide yes)
			(effects
				(font
					(size 1 1)
					(thickness 0.15)
				)
				(justify mirror)
			)
		)
		(property "Author" "Antmicro"
			(at 0 0 90)
			(unlocked yes)
			(layer "B.Fab")
			(hide yes)
			(effects
				(font
					(size 1 1)
					(thickness 0.15)
				)
				(justify mirror)
			)
		)
		(property "License" "Apache-2.0"
			(at 0 0 90)
			(unlocked yes)
			(layer "B.Fab")
			(hide yes)
			(effects
				(font
					(size 1 1)
					(thickness 0.15)
				)
				(justify mirror)
			)
		)
		(sheetname "/Power input/")
		(sheetfile "power_input.kicad_sch")
		(attr exclude_from_pos_files exclude_from_bom)
		(fp_circle
			(center 0 0)
			(end 0.475 0)
			(stroke
				(width 0.05)
				(type default)
			)
			(fill no)
			(layer "B.CrtYd")
		)
		(fp_text user "Author: Antmicro"
			(at -0.4 -3.901 270)
			(layer "B.Fab")
			(effects
				(font
					(size 0.7 0.7)
					(thickness 0.15)
				)
				(justify left bottom mirror)
			)
		)
		(fp_text user "License: Apache-2.0"
			(at -0.4 -5.101 270)
			(layer "B.Fab")
			(effects
				(font
					(size 0.7 0.7)
					(thickness 0.15)
				)
				(justify left bottom mirror)
			)
		)
		(fp_text user "${REFERENCE}"
			(at -0.4 -2.7 270)
			(layer "B.Fab")
			(effects
				(font
					(size 0.7 0.7)
					(thickness 0.15)
				)
				(justify left bottom mirror)
			)
		)
		(pad "1" smd circle
			(at 0 0 90)
			(size 0.75 0.75)
			(layers "B.Cu" "B.Mask")
			(net 40 "+5V")
			(pinfunction "1")
			(pintype "passive")
		)
	)
)
